# BASEBOARD_FAB2 (Tioga Pass) — schematic netlist excerpt (pin names and nets, part order shuffled) for the footprints in the layout excerpt that follows; sources: Cadence DE-HDL packaged netlist, KiCad conversion of Wiwynn_Tioga_Pass_MB.brd

R1U13  RES  51 5.0% CHIP  pkg 0402  page 144 : A = SGPIO_BMC_DOUT_R ; B = SGPIO_BMC_DOUT
C3D10  CAP_A  22.0UF 4V 20% X6S  pkg 0603V  page 76 : A = PVCCMCP_CPU1 ; B = GND
RT47  RES  0 5.0% CHIP  pkg 0603  page 212 : A = VR_PVCCIO_CPU0_PH1_BOOT ; B = VR_PVCCIO_CPU0_PH1_BOOT_R

(kicad_pcb
	(version 20260206)
	(generator "pcbnew")
	(generator_version "10.0")
	(general
		(thickness 1.6)
		(legacy_teardrops no)
	)
	(paper "A4")
	(title_block
		(title "Wiwynn_Tioga_Pass_MB.brd")
		(comment 1 "Tioga Pass / footprints 1466-1468 of 4770")
	)
	(layers
		(0 "F.Cu" signal "TOP")
		(4 "In1.Cu" signal "L2GND")
		(6 "In2.Cu" signal "L3")
		(8 "In3.Cu" signal "L4GND")
		(10 "In4.Cu" signal "L5")
		(12 "In5.Cu" signal "L6GND")
		(14 "In6.Cu" signal "L7VCC")
		(16 "In7.Cu" signal "L8VCC")
		(18 "In8.Cu" signal "L9GND")
		(20 "In9.Cu" signal "L10")
		(22 "In10.Cu" signal "L11GND")
		(24 "In11.Cu" signal "L12")
		(26 "In12.Cu" signal "L13GND")
		(2 "B.Cu" signal "BOTTOM")
		(9 "F.Adhes" user "F.Adhesive")
		(11 "B.Adhes" user "B.Adhesive")
		(13 "F.Paste" user "Package Geometry/Pastemask Top")
		(15 "B.Paste" user "Package Geometry/Pastemask Bottom")
		(5 "F.SilkS" user "Ref Des/Silkscreen Top")
		(7 "B.SilkS" user "Ref Des/Silkscreen Bottom")
		(1 "F.Mask" user "Board Geometry/Soldermask Top")
		(3 "B.Mask" user "Board Geometry/Soldermask Bottom")
		(17 "Dwgs.User" user "User.Drawings")
		(19 "Cmts.User" user "User.Comments")
		(21 "Eco1.User" user "User.Eco1")
		(23 "Eco2.User" user "User.Eco2")
		(25 "Edge.Cuts" user "Board Geometry/Outline")
		(27 "Margin" user)
		(31 "F.CrtYd" user "Package Geometry/Place Bound Top")
		(29 "B.CrtYd" user "Package Geometry/Place Bound Bottom")
		(35 "F.Fab" user "Ref Des/Assembly Top")
		(33 "B.Fab" user "Ref Des/Assembly Bottom")
	)
	(footprint ""
		(layer "F.Cu")
		(at 353.427284 -96.501204 -90)
		(property "Reference" "RT47"
			(at 1.01473 0.656336 180)
			(unlocked yes)
			(layer "F.SilkS")
			(effects
				(font
					(size 0.4064 0.254)
					(thickness 0.1524)
				)
			)
		)
		(property "Value" ""
			(at 0 0 270)
			(layer "F.Fab")
			(effects
				(font
					(size 1.27 1.27)
				)
			)
		)
		(duplicate_pad_numbers_are_jumpers no)
		(fp_poly
			(pts
				(xy -0.4953 -0.2032) (xy 0.4953 -0.2032) (xy 0.4953 1.6002) (xy -0.4953 1.6002)
			)
			(stroke
				(width 0)
				(type default)
			)
			(fill no)
			(layer "F.CrtYd")
		)
		(fp_line
			(start -0.4953 1.6002)
			(end -0.4953 -0.2032)
			(stroke
				(width 0.1)
				(type default)
			)
			(layer "F.Fab")
		)
		(fp_line
			(start 0.4953 1.6002)
			(end -0.4953 1.6002)
			(stroke
				(width 0.1)
				(type default)
			)
			(layer "F.Fab")
		)
		(fp_line
			(start -0.4953 -0.2032)
			(end 0.4953 -0.2032)
			(stroke
				(width 0.1)
				(type default)
			)
			(layer "F.Fab")
		)
		(fp_line
			(start 0.4953 -0.2032)
			(end 0.4953 1.6002)
			(stroke
				(width 0.1)
				(type default)
			)
			(layer "F.Fab")
		)
		(pad "1" smd rect
			(at 0 0 270)
			(size 0.762 0.889)
			(layers "F.Cu" "F.Mask" "F.Paste")
			(net "VR_PVCCIO_CPU0_PH1_BOOT")
		)
		(pad "2" smd rect
			(at 0 1.397 270)
			(size 0.762 0.889)
			(layers "F.Cu" "F.Mask" "F.Paste")
			(net "VR_PVCCIO_CPU0_PH1_BOOT_R")
		)
		(zone
			(layer "F.Cu")
			(hatch none 0.5)
			(connect_pads
				(clearance 0)
			)
			(min_thickness 0.25)
			(keepout
				(tracks not_allowed)
				(vias allowed)
				(pads allowed)
				(copperpour not_allowed)
				(footprints allowed)
			)
			(placement
				(enabled no)
				(sheetname "")
			)
			(fill
				(thermal_gap 0.5)
				(thermal_bridge_width 0.5)
				(island_removal_mode 0)
			)
			(polygon
				(pts
					(xy 352.474784 -96.882204) (xy 352.474784 -96.120204) (xy 352.982784 -96.120204) (xy 352.982784 -96.882204)
				)
			)
		)
		(zone
			(layer "F.Cu")
			(hatch none 0.5)
			(connect_pads
				(clearance 0)
			)
			(min_thickness 0.25)
			(keepout
				(tracks allowed)
				(vias not_allowed)
				(pads allowed)
				(copperpour not_allowed)
				(footprints allowed)
			)
			(placement
				(enabled no)
				(sheetname "")
			)
			(fill
				(thermal_gap 0.5)
				(thermal_bridge_width 0.5)
				(island_removal_mode 0)
			)
			(polygon
				(pts
					(xy 352.474784 -96.120204) (xy 352.982784 -96.120204) (xy 352.982784 -96.882204) (xy 352.474784 -96.882204)
				)
			)
		)
	)
	(footprint ""
		(layer "F.Cu")
		(at 417.481766 -22.049232)
		(property "Reference" "R1U13"
			(at 0 0 0)
			(layer "F.SilkS")
			(hide yes)
			(effects
				(font
					(size 1.27 1.27)
				)
			)
		)
		(property "Value" ""
			(at 0 0 0)
			(layer "F.Fab")
			(effects
				(font
					(size 1.27 1.27)
				)
			)
		)
		(duplicate_pad_numbers_are_jumpers no)
		(fp_poly
			(pts
				(xy -0.2794 -0.1016) (xy 0.2794 -0.1016) (xy 0.2794 0.9906) (xy -0.2794 0.9906)
			)
			(stroke
				(width 0)
				(type default)
			)
			(fill no)
			(layer "F.CrtYd")
		)
		(fp_line
			(start -0.2794 -0.1016)
			(end -0.2794 0.9906)
			(stroke
				(width 0.1)
				(type default)
			)
			(layer "F.Fab")
		)
		(fp_line
			(start -0.2794 0.9906)
			(end 0.2794 0.9906)
			(stroke
				(width 0.1)
				(type default)
			)
			(layer "F.Fab")
		)
		(fp_line
			(start 0.2794 -0.1016)
			(end -0.2794 -0.1016)
			(stroke
				(width 0.1)
				(type default)
			)
			(layer "F.Fab")
		)
		(fp_line
			(start 0.2794 0.9906)
			(end 0.2794 -0.1016)
			(stroke
				(width 0.1)
				(type default)
			)
			(layer "F.Fab")
		)
		(pad "1" smd rect
			(at 0 0)
			(size 0.508 0.508)
			(layers "F.Cu" "F.Mask" "F.Paste")
			(net "SGPIO_BMC_DOUT_R")
		)
		(pad "2" smd rect
			(at 0 0.889)
			(size 0.508 0.508)
			(layers "F.Cu" "F.Mask" "F.Paste")
			(net "SGPIO_BMC_DOUT")
		)
		(zone
			(layer "F.Cu")
			(hatch none 0.5)
			(connect_pads
				(clearance 0)
			)
			(min_thickness 0.25)
			(keepout
				(tracks allowed)
				(vias not_allowed)
				(pads allowed)
				(copperpour not_allowed)
				(footprints allowed)
			)
			(placement
				(enabled no)
				(sheetname "")
			)
			(fill
				(thermal_gap 0.5)
				(thermal_bridge_width 0.5)
				(island_removal_mode 0)
			)
			(polygon
				(pts
					(xy 417.227766 -21.795232) (xy 417.735766 -21.795232) (xy 417.735766 -21.414232) (xy 417.227766 -21.414232)
				)
			)
		)
		(zone
			(layer "F.Cu")
			(hatch none 0.5)
			(connect_pads
				(clearance 0)
			)
			(min_thickness 0.25)
			(keepout
				(tracks not_allowed)
				(vias allowed)
				(pads allowed)
				(copperpour not_allowed)
				(footprints allowed)
			)
			(placement
				(enabled no)
				(sheetname "")
			)
			(fill
				(thermal_gap 0.5)
				(thermal_bridge_width 0.5)
				(island_removal_mode 0)
			)
			(polygon
				(pts
					(xy 417.227766 -21.414232) (xy 417.735766 -21.414232) (xy 417.735766 -21.795232) (xy 417.227766 -21.795232)
				)
			)
		)
	)
	(footprint ""
		(layer "F.Cu")
		(at 106.89844 -77.636116)
		(property "Reference" "C3D10"
			(at 0 0 0)
			(layer "F.SilkS")
			(hide yes)
			(effects
				(font
					(size 1.27 1.27)
				)
			)
		)
		(property "Value" ""
			(at 0 0 0)
			(layer "F.Fab")
			(effects
				(font
					(size 1.27 1.27)
				)
			)
		)
		(duplicate_pad_numbers_are_jumpers no)
		(fp_poly
			(pts
				(xy -0.4953 -0.2032) (xy 0.4953 -0.2032) (xy 0.4953 1.6002) (xy -0.4953 1.6002)
			)
			(stroke
				(width 0)
				(type default)
			)
			(fill no)
			(layer "F.CrtYd")
		)
		(fp_line
			(start -0.4953 -0.2032)
			(end 0.4953 -0.2032)
			(stroke
				(width 0.1)
				(type default)
			)
			(layer "F.Fab")
		)
		(fp_line
			(start -0.4953 1.6002)
			(end -0.4953 -0.2032)
			(stroke
				(width 0.1)
				(type default)
			)
			(layer "F.Fab")
		)
		(fp_line
			(start 0.4953 -0.2032)
			(end 0.4953 1.6002)
			(stroke
				(width 0.1)
				(type default)
			)
			(layer "F.Fab")
		)
		(fp_line
			(start 0.4953 1.6002)
			(end -0.4953 1.6002)
			(stroke
				(width 0.1)
				(type default)
			)
			(layer "F.Fab")
		)
		(pad "1" smd rect
			(at 0 0)
			(size 0.762 0.889)
			(layers "F.Cu" "F.Mask" "F.Paste")
			(net "PVCCMCP_CPU1")
		)
		(pad "2" smd rect
			(at 0 1.397)
			(size 0.762 0.889)
			(layers "F.Cu" "F.Mask" "F.Paste")
			(net "GND")
		)
		(zone
			(layer "F.Cu")
			(hatch none 0.5)
			(connect_pads
				(clearance 0)
			)
			(min_thickness 0.25)
			(keepout
				(tracks not_allowed)
				(vias allowed)
				(pads allowed)
				(copperpour not_allowed)
				(footprints allowed)
			)
			(placement
				(enabled no)
				(sheetname "")
			)
			(fill
				(thermal_gap 0.5)
				(thermal_bridge_width 0.5)
				(island_removal_mode 0)
			)
			(polygon
				(pts
					(xy 106.51744 -77.191616) (xy 107.27944 -77.191616) (xy 107.27944 -76.683616) (xy 106.51744 -76.683616)
				)
			)
		)
	)
)
